(kicad_pcb
	(version 20260206)
	(generator "pcbnew")
	(generator_version "10.0")
	(general
		(thickness 1.6)
		(legacy_teardrops no)
	)
	(paper "A4")
	(title_block
		(title "12092022_DA0F0TMDCD0_F0T_Management_Board_D_brd_V3_OCP.brd")
		(comment 1 "Grand Teton / footprints 1219-1222 of 1440")
	)
	(layers
		(0 "F.Cu" signal "TOP")
		(4 "In1.Cu" signal "GND")
		(6 "In2.Cu" signal "IN1")
		(8 "In3.Cu" signal "GND1")
		(10 "In4.Cu" signal "IN2")
		(12 "In5.Cu" signal "VCC")
		(14 "In6.Cu" signal "VCC1")
		(16 "In7.Cu" signal "IN3")
		(18 "In8.Cu" signal "GND2")
		(20 "In9.Cu" signal "IN4")
		(22 "In10.Cu" signal "GND3")
		(2 "B.Cu" signal "BOTTOM")
		(9 "F.Adhes" user "F.Adhesive")
		(11 "B.Adhes" user "B.Adhesive")
		(13 "F.Paste" user "Package Geometry/Pastemask Top")
		(15 "B.Paste" user "Package Geometry/Pastemask Bottom")
		(5 "F.SilkS" user "Ref Des/Silkscreen Top")
		(7 "B.SilkS" user "Ref Des/Silkscreen Bottom")
		(1 "F.Mask" user "Board Geometry/Soldermask Top")
		(3 "B.Mask" user "Board Geometry/Soldermask Bottom")
		(17 "Dwgs.User" user "User.Drawings")
		(19 "Cmts.User" user "User.Comments")
		(21 "Eco1.User" user "User.Eco1")
		(23 "Eco2.User" user "User.Eco2")
		(25 "Edge.Cuts" user "Board Geometry/Outline")
		(27 "Margin" user)
		(31 "F.CrtYd" user "Package Geometry/Place Bound Top")
		(29 "B.CrtYd" user "Package Geometry/Place Bound Bottom")
		(35 "F.Fab" user "Ref Des/Assembly Top")
		(33 "B.Fab" user "Ref Des/Assembly Bottom")
	)
	(footprint ""
		(layer "B.Cu")
		(at 101.29012 29.261562 90)
		(property "Reference" "J28"
			(at -1.218438 -2.89179 270)
			(unlocked yes)
			(layer "B.SilkS")
			(effects
				(font
					(size 0.7874 0.5842)
					(thickness 0.1524)
				)
				(justify left mirror)
			)
		)
		(property "Value" ""
			(at 0 0 90)
			(layer "B.Fab")
			(effects
				(font
					(size 1.27 1.27)
				)
				(justify mirror)
			)
		)
		(duplicate_pad_numbers_are_jumpers no)
		(fp_line
			(start 1.2192 -2.1082)
			(end -1.2192 -2.1082)
			(stroke
				(width 0.1524)
				(type default)
			)
			(layer "B.SilkS")
		)
		(fp_line
			(start -1.2192 -2.1082)
			(end -1.2192 -0.831596)
			(stroke
				(width 0.1524)
				(type default)
			)
			(layer "B.SilkS")
		)
		(fp_line
			(start -1.2192 0.909574)
			(end -1.2192 2.1082)
			(stroke
				(width 0.1524)
				(type default)
			)
			(layer "B.SilkS")
		)
		(fp_line
			(start 1.2192 2.1082)
			(end 1.2192 -2.1082)
			(stroke
				(width 0.1524)
				(type default)
			)
			(layer "B.SilkS")
		)
		(fp_line
			(start -1.2192 2.1082)
			(end 1.2192 2.1082)
			(stroke
				(width 0.1524)
				(type default)
			)
			(layer "B.SilkS")
		)
		(pad "" np_thru_hole circle
			(at -3.4671 -1.27)
			(size 1.0414 1.0414)
			(drill 1.0414)
			(layers "*.Cu" "*.Mask")
			(clearance 0.381)
			(thermal_gap 0.381)
		)
		(pad "" np_thru_hole circle
			(at -3.4671 1.27)
			(size 1.0414 1.0414)
			(drill 1.0414)
			(layers "*.Cu" "*.Mask")
			(clearance 0.381)
			(thermal_gap 0.381)
		)
		(pad "" np_thru_hole circle
			(at 2.8829 -1.27)
			(size 1.0414 1.0414)
			(drill 1.0414)
			(layers "*.Cu" "*.Mask")
			(clearance 0.381)
			(thermal_gap 0.381)
		)
		(pad "" np_thru_hole circle
			(at 2.8829 1.27)
			(size 1.0414 1.0414)
			(drill 1.0414)
			(layers "*.Cu" "*.Mask")
			(clearance 0.381)
			(thermal_gap 0.381)
		)
		(pad "1" smd rect
			(at -0.8255 -0.249936)
			(size 0.3048 0.508)
			(layers "B.Cu" "B.Mask" "B.Paste")
			(net "85_10INCH_IN1_DN")
		)
		(pad "2" smd rect
			(at -0.8255 0.249936)
			(size 0.3048 0.508)
			(layers "B.Cu" "B.Mask" "B.Paste")
			(net "85_10INCH_IN1_DP")
		)
		(pad "3" smd circle
			(at 0 0 270)
			(size 0 0)
			(layers "B.Cu" "B.Mask" "B.Paste")
			(net "GND_P1")
		)
		(zone
			(layers "F.Cu" "B.Cu" "In1.Cu" "In2.Cu" "In3.Cu" "In4.Cu" "In5.Cu" "In6.Cu"
				"In7.Cu" "In8.Cu" "In9.Cu" "In10.Cu"
			)
			(hatch none 0.5)
			(connect_pads
				(clearance 0)
			)
			(min_thickness 0.25)
			(keepout
				(tracks not_allowed)
				(vias allowed)
				(pads allowed)
				(copperpour not_allowed)
				(footprints allowed)
			)
			(placement
				(enabled no)
				(sheetname "")
			)
			(fill
				(thermal_gap 0.5)
				(thermal_bridge_width 0.5)
				(island_removal_mode 0)
			)
			(polygon
				(pts
					(arc
						(start 100.94722 26.378662)
						(mid 99.09302 26.378662)
						(end 100.94722 26.378662)
					)
				)
			)
		)
		(zone
			(layers "F.Cu" "B.Cu" "In1.Cu" "In2.Cu" "In3.Cu" "In4.Cu" "In5.Cu" "In6.Cu"
				"In7.Cu" "In8.Cu" "In9.Cu" "In10.Cu"
			)
			(hatch none 0.5)
			(connect_pads
				(clearance 0)
			)
			(min_thickness 0.25)
			(keepout
				(tracks not_allowed)
				(vias allowed)
				(pads allowed)
				(copperpour not_allowed)
				(footprints allowed)
			)
			(placement
				(enabled no)
				(sheetname "")
			)
			(fill
				(thermal_gap 0.5)
				(thermal_bridge_width 0.5)
				(island_removal_mode 0)
			)
			(polygon
				(pts
					(arc
						(start 100.94722 32.728662)
						(mid 99.09302 32.728662)
						(end 100.94722 32.728662)
					)
				)
			)
		)
		(zone
			(layers "F.Cu" "B.Cu" "In1.Cu" "In2.Cu" "In3.Cu" "In4.Cu" "In5.Cu" "In6.Cu"
				"In7.Cu" "In8.Cu" "In9.Cu" "In10.Cu"
			)
			(hatch none 0.5)
			(connect_pads
				(clearance 0)
			)
			(min_thickness 0.25)
			(keepout
				(tracks not_allowed)
				(vias allowed)
				(pads allowed)
				(copperpour not_allowed)
				(footprints allowed)
			)
			(placement
				(enabled no)
				(sheetname "")
			)
			(fill
				(thermal_gap 0.5)
				(thermal_bridge_width 0.5)
				(island_removal_mode 0)
			)
			(polygon
				(pts
					(arc
						(start 103.48722 26.378662)
						(mid 101.63302 26.378662)
						(end 103.48722 26.378662)
					)
				)
			)
		)
		(zone
			(layers "F.Cu" "B.Cu" "In1.Cu" "In2.Cu" "In3.Cu" "In4.Cu" "In5.Cu" "In6.Cu"
				"In7.Cu" "In8.Cu" "In9.Cu" "In10.Cu"
			)
			(hatch none 0.5)
			(connect_pads
				(clearance 0)
			)
			(min_thickness 0.25)
			(keepout
				(tracks not_allowed)
				(vias allowed)
				(pads allowed)
				(copperpour not_allowed)
				(footprints allowed)
			)
			(placement
				(enabled no)
				(sheetname "")
			)
			(fill
				(thermal_gap 0.5)
				(thermal_bridge_width 0.5)
				(island_removal_mode 0)
			)
			(polygon
				(pts
					(arc
						(start 103.48722 32.728662)
						(mid 101.63302 32.728662)
						(end 103.48722 32.728662)
					)
				)
			)
		)
		(zone
			(layer "B.Cu")
			(hatch none 0.5)
			(connect_pads
				(clearance 0)
			)
			(min_thickness 0.25)
			(keepout
				(tracks not_allowed)
				(vias allowed)
				(pads allowed)
				(copperpour not_allowed)
				(footprints allowed)
			)
			(placement
				(enabled no)
				(sheetname "")
			)
			(fill
				(thermal_gap 0.5)
				(thermal_bridge_width 0.5)
				(island_removal_mode 0)
			)
			(polygon
				(pts
					(xy 100.74148 30.379162) (xy 100.836984 30.379162) (xy 100.836984 29.782262) (xy 101.243384 29.782262)
					(xy 101.243384 30.379162) (xy 101.336856 30.379162) (xy 101.336856 29.782262) (xy 101.743256 29.782262)
					(xy 101.743256 30.379162) (xy 101.83876 30.379162) (xy 101.83876 29.680662) (xy 100.74148 29.680662)
				)
			)
		)
	)
	(footprint ""
		(layer "B.Cu")
		(at 12.319 -91.44 180)
		(property "Reference" "R271"
			(at 0 0 0)
			(layer "B.SilkS")
			(hide yes)
			(effects
				(font
					(size 1.27 1.27)
				)
				(justify mirror)
			)
		)
		(property "Value" ""
			(at 0 0 0)
			(layer "B.Fab")
			(effects
				(font
					(size 1.27 1.27)
				)
				(justify mirror)
			)
		)
		(duplicate_pad_numbers_are_jumpers no)
		(fp_line
			(start 0.7874 0.4064)
			(end 0.7874 -0.4064)
			(stroke
				(width 0.1524)
				(type default)
			)
			(layer "B.SilkS")
		)
		(fp_line
			(start 0.7874 -0.4064)
			(end -0.7874 -0.4064)
			(stroke
				(width 0.1524)
				(type default)
			)
			(layer "B.SilkS")
		)
		(fp_line
			(start -0.7874 0.4064)
			(end 0.7874 0.4064)
			(stroke
				(width 0.1524)
				(type default)
			)
			(layer "B.SilkS")
		)
		(fp_line
			(start -0.7874 -0.4064)
			(end -0.7874 0.4064)
			(stroke
				(width 0.1524)
				(type default)
			)
			(layer "B.SilkS")
		)
		(fp_line
			(start 0.67945 0.3048)
			(end 0.67945 -0.305054)
			(stroke
				(width 0.1)
				(type default)
			)
			(layer "B.Fab")
		)
		(fp_line
			(start 0.67945 -0.305054)
			(end 0.12065 -0.305054)
			(stroke
				(width 0.1)
				(type default)
			)
			(layer "B.Fab")
		)
		(fp_line
			(start 0.12065 0.3048)
			(end 0.67945 0.3048)
			(stroke
				(width 0.1)
				(type default)
			)
			(layer "B.Fab")
		)
		(fp_line
			(start 0.12065 0.2794)
			(end 0.12065 0.3048)
			(stroke
				(width 0.1)
				(type default)
			)
			(layer "B.Fab")
		)
		(fp_line
			(start 0.12065 -0.2794)
			(end -0.12065 -0.2794)
			(stroke
				(width 0.1)
				(type default)
			)
			(layer "B.Fab")
		)
		(fp_line
			(start 0.12065 -0.305054)
			(end 0.12065 -0.2794)
			(stroke
				(width 0.1)
				(type default)
			)
			(layer "B.Fab")
		)
		(fp_line
			(start -0.120396 0.3048)
			(end -0.120396 0.2794)
			(stroke
				(width 0.1)
				(type default)
			)
			(layer "B.Fab")
		)
		(fp_line
			(start -0.120396 0.2794)
			(end 0.12065 0.2794)
			(stroke
				(width 0.1)
				(type default)
			)
			(layer "B.Fab")
		)
		(fp_line
			(start -0.12065 -0.2794)
			(end -0.12065 -0.3048)
			(stroke
				(width 0.1)
				(type default)
			)
			(layer "B.Fab")
		)
		(fp_line
			(start -0.12065 -0.3048)
			(end -0.67945 -0.3048)
			(stroke
				(width 0.1)
				(type default)
			)
			(layer "B.Fab")
		)
		(fp_line
			(start -0.67945 0.3048)
			(end -0.120396 0.3048)
			(stroke
				(width 0.1)
				(type default)
			)
			(layer "B.Fab")
		)
		(fp_line
			(start -0.67945 -0.3048)
			(end -0.67945 0.3048)
			(stroke
				(width 0.1)
				(type default)
			)
			(layer "B.Fab")
		)
		(pad "1" smd circle
			(at 0.40005 0)
			(size 0 0)
			(layers "B.Cu" "B.Mask" "B.Paste")
			(net "RST_BMC_SELF_HW")
		)
		(pad "2" smd circle
			(at -0.40005 0)
			(size 0 0)
			(layers "B.Cu" "B.Mask" "B.Paste")
			(net "RST_BMC_SELF_HW_R2")
		)
	)
	(footprint ""
		(layer "B.Cu")
		(at 101.267768 119.38635 -90)
		(property "Reference" "J30"
			(at 6.08965 -1.448562 270)
			(unlocked yes)
			(layer "B.SilkS")
			(effects
				(font
					(size 0.7874 0.5842)
					(thickness 0.1524)
				)
				(justify left mirror)
			)
		)
		(property "Value" ""
			(at 0 0 90)
			(layer "B.Fab")
			(effects
				(font
					(size 1.27 1.27)
				)
				(justify mirror)
			)
		)
		(duplicate_pad_numbers_are_jumpers no)
		(fp_line
			(start -1.2192 2.1082)
			(end 1.2192 2.1082)
			(stroke
				(width 0.1524)
				(type default)
			)
			(layer "B.SilkS")
		)
		(fp_line
			(start 1.2192 2.1082)
			(end 1.2192 -2.1082)
			(stroke
				(width 0.1524)
				(type default)
			)
			(layer "B.SilkS")
		)
		(fp_line
			(start -1.2192 0.818388)
			(end -1.2192 2.1082)
			(stroke
				(width 0.1524)
				(type default)
			)
			(layer "B.SilkS")
		)
		(fp_line
			(start -1.2192 -2.1082)
			(end -1.2192 -0.821944)
			(stroke
				(width 0.1524)
				(type default)
			)
			(layer "B.SilkS")
		)
		(fp_line
			(start 1.2192 -2.1082)
			(end -1.2192 -2.1082)
			(stroke
				(width 0.1524)
				(type default)
			)
			(layer "B.SilkS")
		)
		(pad "" np_thru_hole circle
			(at -3.4671 -1.27 180)
			(size 1.0414 1.0414)
			(drill 1.0414)
			(layers "*.Cu" "*.Mask")
			(clearance 0.381)
			(thermal_gap 0.381)
		)
		(pad "" np_thru_hole circle
			(at -3.4671 1.27 180)
			(size 1.0414 1.0414)
			(drill 1.0414)
			(layers "*.Cu" "*.Mask")
			(clearance 0.381)
			(thermal_gap 0.381)
		)
		(pad "" np_thru_hole circle
			(at 2.8829 -1.27 180)
			(size 1.0414 1.0414)
			(drill 1.0414)
			(layers "*.Cu" "*.Mask")
			(clearance 0.381)
			(thermal_gap 0.381)
		)
		(pad "" np_thru_hole circle
			(at 2.8829 1.27 180)
			(size 1.0414 1.0414)
			(drill 1.0414)
			(layers "*.Cu" "*.Mask")
			(clearance 0.381)
			(thermal_gap 0.381)
		)
		(pad "1" smd rect
			(at -0.8255 -0.249936 180)
			(size 0.3048 0.508)
			(layers "B.Cu" "B.Mask" "B.Paste")
			(net "85_10INCH_IN1_DP")
		)
		(pad "2" smd rect
			(at -0.8255 0.249936 180)
			(size 0.3048 0.508)
			(layers "B.Cu" "B.Mask" "B.Paste")
			(net "85_10INCH_IN1_DN")
		)
		(pad "3" smd circle
			(at 0 0 90)
			(size 0 0)
			(layers "B.Cu" "B.Mask" "B.Paste")
			(net "GND_P1")
		)
		(zone
			(layers "F.Cu" "B.Cu" "In1.Cu" "In2.Cu" "In3.Cu" "In4.Cu" "In5.Cu" "In6.Cu"
				"In7.Cu" "In8.Cu" "In9.Cu" "In10.Cu"
			)
			(hatch none 0.5)
			(connect_pads
				(clearance 0)
			)
			(min_thickness 0.25)
			(keepout
				(tracks not_allowed)
				(vias allowed)
				(pads allowed)
				(copperpour not_allowed)
				(footprints allowed)
			)
			(placement
				(enabled no)
				(sheetname "")
			)
			(fill
				(thermal_gap 0.5)
				(thermal_bridge_width 0.5)
				(island_removal_mode 0)
			)
			(polygon
				(pts
					(arc
						(start 100.924868 115.91925)
						(mid 99.070668 115.91925)
						(end 100.924868 115.91925)
					)
				)
			)
		)
		(zone
			(layers "F.Cu" "B.Cu" "In1.Cu" "In2.Cu" "In3.Cu" "In4.Cu" "In5.Cu" "In6.Cu"
				"In7.Cu" "In8.Cu" "In9.Cu" "In10.Cu"
			)
			(hatch none 0.5)
			(connect_pads
				(clearance 0)
			)
			(min_thickness 0.25)
			(keepout
				(tracks not_allowed)
				(vias allowed)
				(pads allowed)
				(copperpour not_allowed)
				(footprints allowed)
			)
			(placement
				(enabled no)
				(sheetname "")
			)
			(fill
				(thermal_gap 0.5)
				(thermal_bridge_width 0.5)
				(island_removal_mode 0)
			)
			(polygon
				(pts
					(arc
						(start 100.924868 122.26925)
						(mid 99.070668 122.26925)
						(end 100.924868 122.26925)
					)
				)
			)
		)
		(zone
			(layers "F.Cu" "B.Cu" "In1.Cu" "In2.Cu" "In3.Cu" "In4.Cu" "In5.Cu" "In6.Cu"
				"In7.Cu" "In8.Cu" "In9.Cu" "In10.Cu"
			)
			(hatch none 0.5)
			(connect_pads
				(clearance 0)
			)
			(min_thickness 0.25)
			(keepout
				(tracks not_allowed)
				(vias allowed)
				(pads allowed)
				(copperpour not_allowed)
				(footprints allowed)
			)
			(placement
				(enabled no)
				(sheetname "")
			)
			(fill
				(thermal_gap 0.5)
				(thermal_bridge_width 0.5)
				(island_removal_mode 0)
			)
			(polygon
				(pts
					(arc
						(start 103.464868 115.91925)
						(mid 101.610668 115.91925)
						(end 103.464868 115.91925)
					)
				)
			)
		)
		(zone
			(layers "F.Cu" "B.Cu" "In1.Cu" "In2.Cu" "In3.Cu" "In4.Cu" "In5.Cu" "In6.Cu"
				"In7.Cu" "In8.Cu" "In9.Cu" "In10.Cu"
			)
			(hatch none 0.5)
			(connect_pads
				(clearance 0)
			)
			(min_thickness 0.25)
			(keepout
				(tracks not_allowed)
				(vias allowed)
				(pads allowed)
				(copperpour not_allowed)
				(footprints allowed)
			)
			(placement
				(enabled no)
				(sheetname "")
			)
			(fill
				(thermal_gap 0.5)
				(thermal_bridge_width 0.5)
				(island_removal_mode 0)
			)
			(polygon
				(pts
					(arc
						(start 103.464868 122.26925)
						(mid 101.610668 122.26925)
						(end 103.464868 122.26925)
					)
				)
			)
		)
		(zone
			(layer "B.Cu")
			(hatch none 0.5)
			(connect_pads
				(clearance 0)
			)
			(min_thickness 0.25)
			(keepout
				(tracks not_allowed)
				(vias allowed)
				(pads allowed)
				(copperpour not_allowed)
				(footprints allowed)
			)
			(placement
				(enabled no)
				(sheetname "")
			)
			(fill
				(thermal_gap 0.5)
				(thermal_bridge_width 0.5)
				(island_removal_mode 0)
			)
			(polygon
				(pts
					(xy 101.816408 118.26875) (xy 101.720904 118.26875) (xy 101.720904 118.86565) (xy 101.314504 118.86565)
					(xy 101.314504 118.26875) (xy 101.221032 118.26875) (xy 101.221032 118.86565) (xy 100.814632 118.86565)
					(xy 100.814632 118.26875) (xy 100.719128 118.26875) (xy 100.719128 118.96725) (xy 101.816408 118.96725)
				)
			)
		)
	)
	(footprint ""
		(layer "B.Cu")
		(at 43.9674 -106.299 180)
		(property "Reference" "U48"
			(at 2.31267 -0.762 270)
			(unlocked yes)
			(layer "B.SilkS")
			(effects
				(font
					(size 0.7874 0.5842)
					(thickness 0.1524)
				)
				(justify left mirror)
			)
		)
		(property "Value" ""
			(at 0 0 0)
			(layer "B.Fab")
			(effects
				(font
					(size 1.27 1.27)
				)
				(justify mirror)
			)
		)
		(duplicate_pad_numbers_are_jumpers no)
		(fp_line
			(start 1.584198 1.500124)
			(end -1.584198 1.500124)
			(stroke
				(width 0.1524)
				(type default)
			)
			(layer "B.SilkS")
		)
		(fp_line
			(start 1.584198 -1.500124)
			(end 1.584198 1.500124)
			(stroke
				(width 0.1524)
				(type default)
			)
			(layer "B.SilkS")
		)
		(fp_line
			(start -1.584198 1.500124)
			(end -1.584198 -1.500124)
			(stroke
				(width 0.1524)
				(type default)
			)
			(layer "B.SilkS")
		)
		(fp_line
			(start -1.584198 -1.500124)
			(end 1.584198 -1.500124)
			(stroke
				(width 0.1524)
				(type default)
			)
			(layer "B.SilkS")
		)
		(fp_line
			(start 0.700024 1.500124)
			(end -0.700024 1.500124)
			(stroke
				(width 0.1)
				(type default)
			)
			(layer "B.Fab")
		)
		(fp_line
			(start 0.700024 -1.500124)
			(end 0.700024 1.500124)
			(stroke
				(width 0.1)
				(type default)
			)
			(layer "B.Fab")
		)
		(fp_line
			(start -0.700024 1.500124)
			(end -0.700024 -1.500124)
			(stroke
				(width 0.1)
				(type default)
			)
			(layer "B.Fab")
		)
		(fp_line
			(start -0.700024 -1.500124)
			(end 0.700024 -1.500124)
			(stroke
				(width 0.1)
				(type default)
			)
			(layer "B.Fab")
		)
		(pad "1" smd rect
			(at 0.999998 -0.94996 90)
			(size 0.8128 0.9144)
			(layers "B.Cu" "B.Mask" "B.Paste")
			(net "P3V_BAT_R")
		)
		(pad "2" smd rect
			(at 0.999998 0.94996 90)
			(size 0.8128 0.9144)
			(layers "B.Cu" "B.Mask" "B.Paste")
			(net "P3V3_AUX")
		)
		(pad "3" smd rect
			(at -0.999998 0 90)
			(size 0.8128 0.9144)
			(layers "B.Cu" "B.Mask" "B.Paste")
			(net "P3V3_RTC_AUX")
		)
	)
)
